# S9S_MB_2U (Grand Teton) — schematic netlist excerpt (pin names and nets, part order shuffled) for the footprints in the layout excerpt that follows; sources: Cadence DE-HDL packaged netlist, KiCad conversion of 03242023_DA0F0TMBIJ0_F0T_Motherboard_J_brd_V01_OCP.brd

C1124  Q_CAP  0.01UF 50V 10% X7R  pkg C0402  page 217 : A = P3V3_AUX_FPGA_VCCIO3 ; B = GND
PR578  Q_RES  100 1% CHIP  pkg 0402LF  page 284 : A = VSENSE_PVCCIN_CPU1_DP ; B = PVCCIN_CPU1

(kicad_pcb
	(version 20260206)
	(generator "pcbnew")
	(generator_version "10.0")
	(general
		(thickness 1.6)
		(legacy_teardrops no)
	)
	(paper "A4")
	(title_block
		(title "03242023_DA0F0TMBIJ0_F0T_Motherboard_J_brd_V01_OCP.brd")
		(comment 1 "Grand Teton / footprints 5338-5339 of 6105")
	)
	(layers
		(0 "F.Cu" signal "TOP")
		(4 "In1.Cu" signal "GND")
		(6 "In2.Cu" signal "IN1")
		(8 "In3.Cu" signal "GND1")
		(10 "In4.Cu" signal "IN2")
		(12 "In5.Cu" signal "GND2")
		(14 "In6.Cu" signal "IN3")
		(16 "In7.Cu" signal "GND3")
		(18 "In8.Cu" signal "VCC")
		(20 "In9.Cu" signal "VCC1")
		(22 "In10.Cu" signal "GND4")
		(24 "In11.Cu" signal "IN4")
		(26 "In12.Cu" signal "GND5")
		(28 "In13.Cu" signal "IN5")
		(30 "In14.Cu" signal "GND6")
		(32 "In15.Cu" signal "IN6")
		(34 "In16.Cu" signal "GND7")
		(2 "B.Cu" signal "BOTTOM")
		(9 "F.Adhes" user "F.Adhesive")
		(11 "B.Adhes" user "B.Adhesive")
		(13 "F.Paste" user "Package Geometry/Pastemask Top")
		(15 "B.Paste" user "Package Geometry/Pastemask Bottom")
		(5 "F.SilkS" user "Ref Des/Silkscreen Top")
		(7 "B.SilkS" user "Ref Des/Silkscreen Bottom")
		(1 "F.Mask" user "Board Geometry/Soldermask Top")
		(3 "B.Mask" user "Board Geometry/Soldermask Bottom")
		(17 "Dwgs.User" user "User.Drawings")
		(19 "Cmts.User" user "User.Comments")
		(21 "Eco1.User" user "User.Eco1")
		(23 "Eco2.User" user "User.Eco2")
		(25 "Edge.Cuts" user "Board Geometry/Outline")
		(27 "Margin" user)
		(31 "F.CrtYd" user "Package Geometry/Place Bound Top")
		(29 "B.CrtYd" user "Package Geometry/Place Bound Bottom")
		(35 "F.Fab" user "Ref Des/Assembly Top")
		(33 "B.Fab" user "Ref Des/Assembly Bottom")
	)
	(footprint ""
		(layer "B.Cu")
		(at 76.413106 -332.627224 90)
		(property "Reference" "PR578"
			(at 0 0 90)
			(layer "B.SilkS")
			(hide yes)
			(effects
				(font
					(size 1.27 1.27)
				)
				(justify mirror)
			)
		)
		(property "Value" ""
			(at 0 0 90)
			(layer "B.Fab")
			(effects
				(font
					(size 1.27 1.27)
				)
				(justify mirror)
			)
		)
		(duplicate_pad_numbers_are_jumpers no)
		(fp_line
			(start 0.7874 -0.4064)
			(end -0.7874 -0.4064)
			(stroke
				(width 0.1524)
				(type default)
			)
			(layer "B.SilkS")
		)
		(fp_line
			(start -0.7874 -0.4064)
			(end -0.7874 0.4064)
			(stroke
				(width 0.1524)
				(type default)
			)
			(layer "B.SilkS")
		)
		(fp_line
			(start 0.7874 0.4064)
			(end 0.7874 -0.4064)
			(stroke
				(width 0.1524)
				(type default)
			)
			(layer "B.SilkS")
		)
		(fp_line
			(start -0.7874 0.4064)
			(end 0.7874 0.4064)
			(stroke
				(width 0.1524)
				(type default)
			)
			(layer "B.SilkS")
		)
		(fp_line
			(start 0.67945 -0.305054)
			(end 0.12065 -0.305054)
			(stroke
				(width 0.1)
				(type default)
			)
			(layer "B.Fab")
		)
		(fp_line
			(start 0.12065 -0.305054)
			(end 0.12065 -0.2794)
			(stroke
				(width 0.1)
				(type default)
			)
			(layer "B.Fab")
		)
		(fp_line
			(start -0.12065 -0.3048)
			(end -0.67945 -0.3048)
			(stroke
				(width 0.1)
				(type default)
			)
			(layer "B.Fab")
		)
		(fp_line
			(start -0.67945 -0.3048)
			(end -0.67945 0.3048)
			(stroke
				(width 0.1)
				(type default)
			)
			(layer "B.Fab")
		)
		(fp_line
			(start 0.12065 -0.2794)
			(end -0.12065 -0.2794)
			(stroke
				(width 0.1)
				(type default)
			)
			(layer "B.Fab")
		)
		(fp_line
			(start -0.12065 -0.2794)
			(end -0.12065 -0.3048)
			(stroke
				(width 0.1)
				(type default)
			)
			(layer "B.Fab")
		)
		(fp_line
			(start 0.12065 0.2794)
			(end 0.12065 0.3048)
			(stroke
				(width 0.1)
				(type default)
			)
			(layer "B.Fab")
		)
		(fp_line
			(start -0.120396 0.2794)
			(end 0.12065 0.2794)
			(stroke
				(width 0.1)
				(type default)
			)
			(layer "B.Fab")
		)
		(fp_line
			(start 0.67945 0.3048)
			(end 0.67945 -0.305054)
			(stroke
				(width 0.1)
				(type default)
			)
			(layer "B.Fab")
		)
		(fp_line
			(start 0.12065 0.3048)
			(end 0.67945 0.3048)
			(stroke
				(width 0.1)
				(type default)
			)
			(layer "B.Fab")
		)
		(fp_line
			(start -0.120396 0.3048)
			(end -0.120396 0.2794)
			(stroke
				(width 0.1)
				(type default)
			)
			(layer "B.Fab")
		)
		(fp_line
			(start -0.67945 0.3048)
			(end -0.120396 0.3048)
			(stroke
				(width 0.1)
				(type default)
			)
			(layer "B.Fab")
		)
		(pad "1" smd circle
			(at 0.40005 0 270)
			(size 0 0)
			(layers "B.Cu" "B.Mask" "B.Paste")
			(net "VSENSE_PVCCIN_CPU1_DP")
		)
		(pad "2" smd circle
			(at -0.40005 0 270)
			(size 0 0)
			(layers "B.Cu" "B.Mask" "B.Paste")
			(net "PVCCIN_CPU1")
		)
	)
	(footprint ""
		(layer "B.Cu")
		(at 183.755538 -105.375456 90)
		(property "Reference" "C1124"
			(at 0 0 90)
			(layer "B.SilkS")
			(hide yes)
			(effects
				(font
					(size 1.27 1.27)
				)
				(justify mirror)
			)
		)
		(property "Value" ""
			(at 0 0 90)
			(layer "B.Fab")
			(effects
				(font
					(size 1.27 1.27)
				)
				(justify mirror)
			)
		)
		(duplicate_pad_numbers_are_jumpers no)
		(fp_line
			(start 0.69215 -0.2921)
			(end -0.69215 -0.2921)
			(stroke
				(width 0.1524)
				(type default)
			)
			(layer "B.SilkS")
		)
		(fp_line
			(start -0.69215 -0.2921)
			(end -0.69215 0.2921)
			(stroke
				(width 0.1524)
				(type default)
			)
			(layer "B.SilkS")
		)
		(fp_line
			(start 0.69215 0.2921)
			(end 0.69215 -0.2921)
			(stroke
				(width 0.1524)
				(type default)
			)
			(layer "B.SilkS")
		)
		(fp_line
			(start -0.69215 0.2921)
			(end 0.69215 0.2921)
			(stroke
				(width 0.1524)
				(type default)
			)
			(layer "B.SilkS")
		)
		(fp_line
			(start 0.51435 -0.2794)
			(end -0.51435 -0.2794)
			(stroke
				(width 0.1)
				(type default)
			)
			(layer "B.Fab")
		)
		(fp_line
			(start -0.51435 -0.2794)
			(end -0.51435 0.2794)
			(stroke
				(width 0.1)
				(type default)
			)
			(layer "B.Fab")
		)
		(fp_line
			(start 0.51435 0.2794)
			(end 0.51435 -0.2794)
			(stroke
				(width 0.1)
				(type default)
			)
			(layer "B.Fab")
		)
		(fp_line
			(start -0.51435 0.2794)
			(end 0.51435 0.2794)
			(stroke
				(width 0.1)
				(type default)
			)
			(layer "B.Fab")
		)
		(pad "1" smd circle
			(at 0.40005 0 270)
			(size 0 0)
			(layers "B.Cu" "B.Mask" "B.Paste")
			(net "P3V3_AUX_FPGA_VCCIO3")
		)
		(pad "2" smd circle
			(at -0.40005 0 270)
			(size 0 0)
			(layers "B.Cu" "B.Mask" "B.Paste")
			(net "GND")
		)
		(zone
			(layer "B.Cu")
			(hatch none 0.5)
			(connect_pads
				(clearance 0)
			)
			(min_thickness 0.25)
			(keepout
				(tracks not_allowed)
				(vias allowed)
				(pads allowed)
				(copperpour not_allowed)
				(footprints allowed)
			)
			(placement
				(enabled no)
				(sheetname "")
			)
			(fill
				(thermal_gap 0.5)
				(thermal_bridge_width 0.5)
				(island_removal_mode 0)
			)
			(polygon
				(pts
					(xy 183.843168 -105.565956) (xy 183.901334 -105.474516) (xy 183.901334 -105.275126) (xy 183.843168 -105.184956)
					(xy 183.667908 -105.184956) (xy 183.609488 -105.275126) (xy 183.609488 -105.474516) (xy 183.667654 -105.565956)
				)
			)
		)
	)
)
